(kicad_pcb
	(version 20241229)
	(generator "pcbnew")
	(generator_version "9.0")
	(general
		(thickness 1.63)
		(legacy_teardrops no)
	)
	(paper "A4")
	(title_block
		(title "CM4 Baseboard")
		(date "2026-01-05")
		(rev "1.1.1")
		(company "Antmicro Ltd")
		(comment 1 "www.antmicro.com")
		(comment 9 "footprint 274 of 506 (J201), pads 99-100 of 100")
	)
	(layers
		(0 "F.Cu" signal)
		(4 "In1.Cu" power)
		(6 "In2.Cu" power)
		(8 "In3.Cu" signal)
		(10 "In4.Cu" signal)
		(2 "B.Cu" signal)
		(9 "F.Adhes" user "F.Adhesive")
		(11 "B.Adhes" user "B.Adhesive")
		(13 "F.Paste" user)
		(15 "B.Paste" user)
		(5 "F.SilkS" user "F.Silkscreen")
		(7 "B.SilkS" user "B.Silkscreen")
		(1 "F.Mask" user)
		(3 "B.Mask" user)
		(17 "Dwgs.User" user "User.Drawings")
		(19 "Cmts.User" user "User.Comments")
		(21 "Eco1.User" user "User.Eco1")
		(23 "Eco2.User" user "User.Eco2")
		(25 "Edge.Cuts" user)
		(27 "Margin" user)
		(31 "F.CrtYd" user "F.Courtyard")
		(29 "B.CrtYd" user "B.Courtyard")
		(35 "F.Fab" user)
		(33 "B.Fab" user)
	)
	(footprint "antmicro-footprints:Conn_Socket_Hirose_DF40_2x50_DF40HC-3.0-100DS-0.4V"
		(layer "F.Cu")
		(at 80.020961 154.714 -90)
		(property "Reference" "J201"
			(at -10.2975 1.652999 90)
			(layer "F.SilkS")
			(effects
				(font
					(size 0.7 0.7)
					(thickness 0.15)
				)
				(justify left bottom)
			)
		)
		(property "Value" "Socket_Hirose_DF40_2x50_DF40HC-3.0-100DS-0.4V"
			(at 0 3.25 90)
			(layer "F.Fab")
			(effects
				(font
					(size 0.7 0.7)
					(thickness 0.15)
				)
				(justify left bottom)
			)
		)
		(property "Datasheet" "https://www.hirose.com/en/product/document?clcode=CL0684-4151-0-51&productname=DF40HC(3.0)-100DS-0.4V(51&series=DF40&documenttype=Catalog&lang=en&documentid=en_DF40_CAT"
			(at 0 0 270)
			(layer "F.Fab")
			(hide yes)
			(effects
				(font
					(size 1.27 1.27)
					(thickness 0.15)
				)
			)
		)
		(property "Manufacturer" "Hirose Electric"
			(at 0 0 270)
			(unlocked yes)
			(layer "F.Fab")
			(hide yes)
			(effects
				(font
					(size 1 1)
					(thickness 0.15)
				)
			)
		)
		(property "MPN" "DF40HC(3.0)-100DS-0.4V(51)"
			(at 0 0 270)
			(unlocked yes)
			(layer "F.Fab")
			(hide yes)
			(effects
				(font
					(size 1 1)
					(thickness 0.15)
				)
			)
		)
		(property "Author" "Antmicro"
			(at 0 0 270)
			(unlocked yes)
			(layer "F.Fab")
			(hide yes)
			(effects
				(font
					(size 1 1)
					(thickness 0.15)
				)
			)
		)
		(property "License" "Apache-2.0"
			(at 0 0 270)
			(unlocked yes)
			(layer "F.Fab")
			(hide yes)
			(effects
				(font
					(size 1 1)
					(thickness 0.15)
				)
			)
		)
		(property "Pitch" "0.4 mm"
			(at 0 0 270)
			(unlocked yes)
			(layer "F.Fab")
			(hide yes)
			(effects
				(font
					(size 1 1)
					(thickness 0.15)
				)
			)
		)
		(sheetname "/Compute module/")
		(sheetfile "compute-module.kicad_sch")
		(attr smd)
		(pad "99" smd rect
			(at 9.803 1.547 270)
			(size 0.2 0.7)
			(layers "F.Cu" "F.Mask" "F.Paste")
			(net 255 "/Compute module/~{RPi_RST}")
			(pintype "passive")
		)
		(pad "100" smd rect
			(at 9.803 -1.534 270)
			(size 0.2 0.7)
			(layers "F.Cu" "F.Mask" "F.Paste")
			(net 128 "/Compute module/nEXTRST")
			(pintype "passive")
		)
	)
)
